(kicad_pcb
	(version 20260206)
	(generator "pcbnew")
	(generator_version "10.0")
	(general
		(thickness 1.6)
		(legacy_teardrops no)
	)
	(paper "A4")
	(title_block
		(title "v1-chassis-manager — T6M_CM_d_v01_1031_1645.brd")
		(comment 1 "Open CloudServer (Microsoft) / footprints 2384-2393 of 2512")
	)
	(layers
		(0 "F.Cu" signal "TOP")
		(4 "In1.Cu" signal "GND1")
		(6 "In2.Cu" signal "IN1")
		(8 "In3.Cu" signal "VCC1")
		(10 "In4.Cu" signal "VCC2")
		(12 "In5.Cu" signal "GND2")
		(14 "In6.Cu" signal "IN2")
		(16 "In7.Cu" signal "IN3")
		(18 "In8.Cu" signal "GND3")
		(2 "B.Cu" signal "BOTTOM")
		(9 "F.Adhes" user "F.Adhesive")
		(11 "B.Adhes" user "B.Adhesive")
		(13 "F.Paste" user "Package Geometry/Pastemask Top")
		(15 "B.Paste" user "Package Geometry/Pastemask Bottom")
		(5 "F.SilkS" user "Ref Des/Silkscreen Top")
		(7 "B.SilkS" user "Ref Des/Silkscreen Bottom")
		(1 "F.Mask" user "Board Geometry/Soldermask Top")
		(3 "B.Mask" user "Board Geometry/Soldermask Bottom")
		(17 "Dwgs.User" user "User.Drawings")
		(19 "Cmts.User" user "User.Comments")
		(21 "Eco1.User" user "User.Eco1")
		(23 "Eco2.User" user "User.Eco2")
		(25 "Edge.Cuts" user "Board Geometry/Outline")
		(27 "Margin" user)
		(31 "F.CrtYd" user "Package Geometry/Place Bound Top")
		(29 "B.CrtYd" user "Package Geometry/Place Bound Bottom")
		(35 "F.Fab" user "Ref Des/Assembly Top")
		(33 "B.Fab" user "Ref Des/Assembly Bottom")
	)
	(footprint ""
		(layer "B.Cu")
		(at 54.028086 -123.152662 90)
		(property "Reference" "C297"
			(at -55.125874 -42.362628 270)
			(unlocked yes)
			(layer "B.SilkS")
			(effects
				(font
					(size 0.7874 0.5842)
					(thickness 0.1524)
				)
				(justify left mirror)
			)
		)
		(property "Value" ""
			(at 0 0 90)
			(layer "B.Fab")
			(effects
				(font
					(size 1.27 1.27)
				)
				(justify mirror)
			)
		)
		(duplicate_pad_numbers_are_jumpers no)
		(fp_line
			(start 0.7874 -0.4064)
			(end -0.7874 -0.4064)
			(stroke
				(width 0.1524)
				(type default)
			)
			(layer "B.SilkS")
		)
		(fp_line
			(start -0.7874 -0.4064)
			(end -0.7874 0.4064)
			(stroke
				(width 0.1524)
				(type default)
			)
			(layer "B.SilkS")
		)
		(fp_line
			(start 0 0.381)
			(end 0 -0.381)
			(stroke
				(width 0.1524)
				(type default)
			)
			(layer "B.SilkS")
		)
		(fp_line
			(start 0.7874 0.4064)
			(end 0.7874 -0.4064)
			(stroke
				(width 0.1524)
				(type default)
			)
			(layer "B.SilkS")
		)
		(fp_line
			(start -0.7874 0.4064)
			(end 0.7874 0.4064)
			(stroke
				(width 0.1524)
				(type default)
			)
			(layer "B.SilkS")
		)
		(fp_poly
			(pts
				(xy 0.5334 0.254) (xy 0.635 0.254) (xy 0.635 0.2286) (xy 0.635 -0.254) (xy 0.5334 -0.254) (xy 0.5334 -0.2794)
				(xy -0.5334 -0.2794) (xy -0.5334 -0.254) (xy -0.635 -0.254) (xy -0.635 0.254) (xy -0.5334 0.254)
				(xy -0.5334 0.2794) (xy 0.508 0.2794) (xy 0.5334 0.2794)
			)
			(stroke
				(width 0)
				(type default)
			)
			(fill no)
			(layer "B.CrtYd")
		)
		(pad "1" smd rect
			(at -0.40005 0 270)
			(size 0.4572 0.508)
			(layers "B.Cu" "B.Mask" "B.Paste")
			(net "BMC_NODE1_V1PLLAV12")
		)
		(pad "2" smd rect
			(at 0.40005 0 270)
			(size 0.4572 0.508)
			(layers "B.Cu" "B.Mask" "B.Paste")
			(net "GND")
		)
	)
	(footprint ""
		(layer "B.Cu")
		(at 139.93876 -187.872624 -90)
		(property "Reference" "C624"
			(at -4.565396 1.448308 270)
			(unlocked yes)
			(layer "B.SilkS")
			(effects
				(font
					(size 0.7874 0.5842)
					(thickness 0.1524)
				)
				(justify left mirror)
			)
		)
		(property "Value" ""
			(at 0 0 90)
			(layer "B.Fab")
			(effects
				(font
					(size 1.27 1.27)
				)
				(justify mirror)
			)
		)
		(duplicate_pad_numbers_are_jumpers no)
		(fp_line
			(start -0.7874 0.4064)
			(end 0.7874 0.4064)
			(stroke
				(width 0.1524)
				(type default)
			)
			(layer "B.SilkS")
		)
		(fp_line
			(start 0.7874 0.4064)
			(end 0.7874 -0.4064)
			(stroke
				(width 0.1524)
				(type default)
			)
			(layer "B.SilkS")
		)
		(fp_line
			(start 0 0.381)
			(end 0 -0.381)
			(stroke
				(width 0.1524)
				(type default)
			)
			(layer "B.SilkS")
		)
		(fp_line
			(start -0.7874 -0.4064)
			(end -0.7874 0.4064)
			(stroke
				(width 0.1524)
				(type default)
			)
			(layer "B.SilkS")
		)
		(fp_line
			(start 0.7874 -0.4064)
			(end -0.7874 -0.4064)
			(stroke
				(width 0.1524)
				(type default)
			)
			(layer "B.SilkS")
		)
		(fp_poly
			(pts
				(xy 0.5334 0.254) (xy 0.635 0.254) (xy 0.635 0.2286) (xy 0.635 -0.254) (xy 0.5334 -0.254) (xy 0.5334 -0.2794)
				(xy -0.5334 -0.2794) (xy -0.5334 -0.254) (xy -0.635 -0.254) (xy -0.635 0.254) (xy -0.5334 0.254)
				(xy -0.5334 0.2794) (xy 0.508 0.2794) (xy 0.5334 0.2794)
			)
			(stroke
				(width 0)
				(type default)
			)
			(fill no)
			(layer "B.CrtYd")
		)
		(pad "1" smd rect
			(at -0.40005 0 90)
			(size 0.4572 0.508)
			(layers "B.Cu" "B.Mask" "B.Paste")
			(net "T9_NODE1_EN_R")
		)
		(pad "2" smd rect
			(at 0.40005 0 90)
			(size 0.4572 0.508)
			(layers "B.Cu" "B.Mask" "B.Paste")
			(net "GND")
		)
	)
	(footprint ""
		(layer "B.Cu")
		(at 125.49251 -124.26315 90)
		(property "Reference" "R3"
			(at 2.12979 0.033782 270)
			(unlocked yes)
			(layer "B.SilkS")
			(effects
				(font
					(size 0.7874 0.5842)
					(thickness 0.1524)
				)
				(justify mirror)
			)
		)
		(property "Value" ""
			(at 0 0 90)
			(layer "B.Fab")
			(effects
				(font
					(size 1.27 1.27)
				)
				(justify mirror)
			)
		)
		(duplicate_pad_numbers_are_jumpers no)
		(fp_line
			(start 1.2954 -0.5842)
			(end -1.2954 -0.5842)
			(stroke
				(width 0.1524)
				(type default)
			)
			(layer "B.SilkS")
		)
		(fp_line
			(start -1.2954 -0.5842)
			(end -1.2954 0.5842)
			(stroke
				(width 0.1524)
				(type default)
			)
			(layer "B.SilkS")
		)
		(fp_line
			(start 1.2954 0.5842)
			(end 1.2954 -0.5842)
			(stroke
				(width 0.1524)
				(type default)
			)
			(layer "B.SilkS")
		)
		(fp_line
			(start -1.2954 0.5842)
			(end 1.2954 0.5842)
			(stroke
				(width 0.1524)
				(type default)
			)
			(layer "B.SilkS")
		)
		(fp_poly
			(pts
				(xy -1.143 -0.3556) (xy -1.143 0.3556) (xy -0.8636 0.3556) (xy -0.8636 0.4572) (xy 0.8636 0.4572)
				(xy 0.8636 0.4318) (xy 0.8636 0.3556) (xy 1.143 0.3556) (xy 1.143 -0.3556) (xy 0.8636 -0.3556) (xy 0.8636 -0.4572)
				(xy -0.8636 -0.4572) (xy -0.8636 -0.3556)
			)
			(stroke
				(width 0)
				(type default)
			)
			(fill no)
			(layer "B.CrtYd")
		)
		(pad "1" smd rect
			(at -0.7366 0 180)
			(size 0.7112 0.8128)
			(layers "B.Cu" "B.Mask" "B.Paste")
			(net "P1V05_NODE1")
		)
		(pad "2" smd rect
			(at 0.7366 0 180)
			(size 0.7112 0.8128)
			(layers "B.Cu" "B.Mask" "B.Paste")
			(net "P1V05_CLK_NODE1_R")
		)
	)
	(footprint ""
		(layer "B.Cu")
		(at 70.278752 -98.467926)
		(property "Reference" "R92"
			(at 2.51841 1.571498 0)
			(unlocked yes)
			(layer "B.SilkS")
			(effects
				(font
					(size 0.7874 0.5842)
					(thickness 0.1524)
				)
				(justify left mirror)
			)
		)
		(property "Value" ""
			(at 0 0 0)
			(layer "B.Fab")
			(effects
				(font
					(size 1.27 1.27)
				)
				(justify mirror)
			)
		)
		(duplicate_pad_numbers_are_jumpers no)
		(fp_line
			(start -0.7874 -0.4064)
			(end -0.7874 0.4064)
			(stroke
				(width 0.1524)
				(type default)
			)
			(layer "B.SilkS")
		)
		(fp_line
			(start -0.7874 0.4064)
			(end 0.7874 0.4064)
			(stroke
				(width 0.1524)
				(type default)
			)
			(layer "B.SilkS")
		)
		(fp_line
			(start 0.7874 -0.4064)
			(end -0.7874 -0.4064)
			(stroke
				(width 0.1524)
				(type default)
			)
			(layer "B.SilkS")
		)
		(fp_line
			(start 0.7874 0.4064)
			(end 0.7874 -0.4064)
			(stroke
				(width 0.1524)
				(type default)
			)
			(layer "B.SilkS")
		)
		(fp_poly
			(pts
				(xy 0.508 0.2794) (xy 0.508 0.2286) (xy 0.635 0.2286) (xy 0.635 -0.254) (xy 0.5334 -0.254) (xy 0.5334 -0.2794)
				(xy -0.5334 -0.2794) (xy -0.5334 -0.254) (xy -0.635 -0.254) (xy -0.635 0.254) (xy -0.5334 0.254)
				(xy -0.5334 0.2794)
			)
			(stroke
				(width 0)
				(type default)
			)
			(fill no)
			(layer "B.CrtYd")
		)
		(pad "1" smd rect
			(at -0.40005 0 180)
			(size 0.4572 0.508)
			(layers "B.Cu" "B.Mask" "B.Paste")
			(net "GND")
		)
		(pad "2" smd rect
			(at 0.40005 0 180)
			(size 0.4572 0.508)
			(layers "B.Cu" "B.Mask" "B.Paste")
			(net "NODE1_BIOS_MB_REV_ID1")
		)
	)
	(footprint ""
		(layer "B.Cu")
		(at 67.879468 -138.45032 -90)
		(property "Reference" "C243"
			(at 55.985156 38.169342 270)
			(unlocked yes)
			(layer "B.SilkS")
			(effects
				(font
					(size 0.7874 0.5842)
					(thickness 0.1524)
				)
				(justify left mirror)
			)
		)
		(property "Value" ""
			(at 0 0 90)
			(layer "B.Fab")
			(effects
				(font
					(size 1.27 1.27)
				)
				(justify mirror)
			)
		)
		(duplicate_pad_numbers_are_jumpers no)
		(fp_line
			(start -0.7874 0.4064)
			(end 0.7874 0.4064)
			(stroke
				(width 0.1524)
				(type default)
			)
			(layer "B.SilkS")
		)
		(fp_line
			(start 0.7874 0.4064)
			(end 0.7874 -0.4064)
			(stroke
				(width 0.1524)
				(type default)
			)
			(layer "B.SilkS")
		)
		(fp_line
			(start 0 0.381)
			(end 0 -0.381)
			(stroke
				(width 0.1524)
				(type default)
			)
			(layer "B.SilkS")
		)
		(fp_line
			(start -0.7874 -0.4064)
			(end -0.7874 0.4064)
			(stroke
				(width 0.1524)
				(type default)
			)
			(layer "B.SilkS")
		)
		(fp_line
			(start 0.7874 -0.4064)
			(end -0.7874 -0.4064)
			(stroke
				(width 0.1524)
				(type default)
			)
			(layer "B.SilkS")
		)
		(fp_poly
			(pts
				(xy 0.5334 0.254) (xy 0.635 0.254) (xy 0.635 0.2286) (xy 0.635 -0.254) (xy 0.5334 -0.254) (xy 0.5334 -0.2794)
				(xy -0.5334 -0.2794) (xy -0.5334 -0.254) (xy -0.635 -0.254) (xy -0.635 0.254) (xy -0.5334 0.254)
				(xy -0.5334 0.2794) (xy 0.508 0.2794) (xy 0.5334 0.2794)
			)
			(stroke
				(width 0)
				(type default)
			)
			(fill no)
			(layer "B.CrtYd")
		)
		(pad "1" smd rect
			(at -0.40005 0 90)
			(size 0.4572 0.508)
			(layers "B.Cu" "B.Mask" "B.Paste")
			(net "P3V3_NODE1")
		)
		(pad "2" smd rect
			(at 0.40005 0 90)
			(size 0.4572 0.508)
			(layers "B.Cu" "B.Mask" "B.Paste")
			(net "GND")
		)
	)
	(footprint ""
		(layer "B.Cu")
		(at 156.828998 -154.64663)
		(property "Reference" "C470"
			(at -3.44805 -0.463042 0)
			(unlocked yes)
			(layer "B.SilkS")
			(effects
				(font
					(size 0.7874 0.5842)
					(thickness 0.1524)
				)
				(justify left mirror)
			)
		)
		(property "Value" ""
			(at 0 0 0)
			(layer "B.Fab")
			(effects
				(font
					(size 1.27 1.27)
				)
				(justify mirror)
			)
		)
		(duplicate_pad_numbers_are_jumpers no)
		(fp_line
			(start -0.7874 -0.4064)
			(end -0.7874 0.4064)
			(stroke
				(width 0.1524)
				(type default)
			)
			(layer "B.SilkS")
		)
		(fp_line
			(start -0.7874 0.4064)
			(end 0.7874 0.4064)
			(stroke
				(width 0.1524)
				(type default)
			)
			(layer "B.SilkS")
		)
		(fp_line
			(start 0 0.381)
			(end 0 -0.381)
			(stroke
				(width 0.1524)
				(type default)
			)
			(layer "B.SilkS")
		)
		(fp_line
			(start 0.7874 -0.4064)
			(end -0.7874 -0.4064)
			(stroke
				(width 0.1524)
				(type default)
			)
			(layer "B.SilkS")
		)
		(fp_line
			(start 0.7874 0.4064)
			(end 0.7874 -0.4064)
			(stroke
				(width 0.1524)
				(type default)
			)
			(layer "B.SilkS")
		)
		(fp_poly
			(pts
				(xy 0.5334 0.254) (xy 0.635 0.254) (xy 0.635 0.2286) (xy 0.635 -0.254) (xy 0.5334 -0.254) (xy 0.5334 -0.2794)
				(xy -0.5334 -0.2794) (xy -0.5334 -0.254) (xy -0.635 -0.254) (xy -0.635 0.254) (xy -0.5334 0.254)
				(xy -0.5334 0.2794) (xy 0.508 0.2794) (xy 0.5334 0.2794)
			)
			(stroke
				(width 0)
				(type default)
			)
			(fill no)
			(layer "B.CrtYd")
		)
		(pad "1" smd rect
			(at -0.40005 0 180)
			(size 0.4572 0.508)
			(layers "B.Cu" "B.Mask" "B.Paste")
			(net "P1V9_LAN2")
		)
		(pad "2" smd rect
			(at 0.40005 0 180)
			(size 0.4572 0.508)
			(layers "B.Cu" "B.Mask" "B.Paste")
			(net "GND")
		)
	)
	(footprint ""
		(layer "B.Cu")
		(at 151.572214 -64.971422 -90)
		(property "Reference" "C346"
			(at 2.01422 -5.959602 270)
			(unlocked yes)
			(layer "B.SilkS")
			(effects
				(font
					(size 0.7874 0.5842)
					(thickness 0.1524)
				)
				(justify left mirror)
			)
		)
		(property "Value" ""
			(at 0 0 90)
			(layer "B.Fab")
			(effects
				(font
					(size 1.27 1.27)
				)
				(justify mirror)
			)
		)
		(duplicate_pad_numbers_are_jumpers no)
		(fp_line
			(start -0.7874 0.4064)
			(end 0.7874 0.4064)
			(stroke
				(width 0.1524)
				(type default)
			)
			(layer "B.SilkS")
		)
		(fp_line
			(start 0.7874 0.4064)
			(end 0.7874 -0.4064)
			(stroke
				(width 0.1524)
				(type default)
			)
			(layer "B.SilkS")
		)
		(fp_line
			(start 0 0.381)
			(end 0 -0.381)
			(stroke
				(width 0.1524)
				(type default)
			)
			(layer "B.SilkS")
		)
		(fp_line
			(start -0.7874 -0.4064)
			(end -0.7874 0.4064)
			(stroke
				(width 0.1524)
				(type default)
			)
			(layer "B.SilkS")
		)
		(fp_line
			(start 0.7874 -0.4064)
			(end -0.7874 -0.4064)
			(stroke
				(width 0.1524)
				(type default)
			)
			(layer "B.SilkS")
		)
		(fp_poly
			(pts
				(xy 0.5334 0.254) (xy 0.635 0.254) (xy 0.635 0.2286) (xy 0.635 -0.254) (xy 0.5334 -0.254) (xy 0.5334 -0.2794)
				(xy -0.5334 -0.2794) (xy -0.5334 -0.254) (xy -0.635 -0.254) (xy -0.635 0.254) (xy -0.5334 0.254)
				(xy -0.5334 0.2794) (xy 0.508 0.2794) (xy 0.5334 0.2794)
			)
			(stroke
				(width 0)
				(type default)
			)
			(fill no)
			(layer "B.CrtYd")
		)
		(pad "1" smd rect
			(at -0.40005 0 90)
			(size 0.4572 0.508)
			(layers "B.Cu" "B.Mask" "B.Paste")
			(net "P1V8_SATA_VAA2_0_NODE1")
		)
		(pad "2" smd rect
			(at 0.40005 0 90)
			(size 0.4572 0.508)
			(layers "B.Cu" "B.Mask" "B.Paste")
			(net "GND")
		)
	)
	(footprint ""
		(layer "B.Cu")
		(at 95.26524 -181.616604 180)
		(property "Reference" "R145"
			(at 0.29972 -1.595628 0)
			(unlocked yes)
			(layer "B.SilkS")
			(effects
				(font
					(size 0.7874 0.5842)
					(thickness 0.1524)
				)
				(justify left mirror)
			)
		)
		(property "Value" ""
			(at 0 0 0)
			(layer "B.Fab")
			(effects
				(font
					(size 1.27 1.27)
				)
				(justify mirror)
			)
		)
		(duplicate_pad_numbers_are_jumpers no)
		(fp_line
			(start 0.7874 0.4064)
			(end 0.7874 -0.4064)
			(stroke
				(width 0.1524)
				(type default)
			)
			(layer "B.SilkS")
		)
		(fp_line
			(start 0.7874 -0.4064)
			(end -0.7874 -0.4064)
			(stroke
				(width 0.1524)
				(type default)
			)
			(layer "B.SilkS")
		)
		(fp_line
			(start -0.7874 0.4064)
			(end 0.7874 0.4064)
			(stroke
				(width 0.1524)
				(type default)
			)
			(layer "B.SilkS")
		)
		(fp_line
			(start -0.7874 -0.4064)
			(end -0.7874 0.4064)
			(stroke
				(width 0.1524)
				(type default)
			)
			(layer "B.SilkS")
		)
		(fp_poly
			(pts
				(xy 0.508 0.2794) (xy 0.508 0.2286) (xy 0.635 0.2286) (xy 0.635 -0.254) (xy 0.5334 -0.254) (xy 0.5334 -0.2794)
				(xy -0.5334 -0.2794) (xy -0.5334 -0.254) (xy -0.635 -0.254) (xy -0.635 0.254) (xy -0.5334 0.254)
				(xy -0.5334 0.2794)
			)
			(stroke
				(width 0)
				(type default)
			)
			(fill no)
			(layer "B.CrtYd")
		)
		(pad "1" smd rect
			(at -0.40005 0)
			(size 0.4572 0.508)
			(layers "B.Cu" "B.Mask" "B.Paste")
			(net "CM_STATUS_LED_N")
		)
		(pad "2" smd rect
			(at 0.40005 0)
			(size 0.4572 0.508)
			(layers "B.Cu" "B.Mask" "B.Paste")
			(net "P3V3_NODE1")
		)
	)
	(footprint ""
		(layer "B.Cu")
		(at 111.99876 -185.205624 90)
		(property "Reference" "R964"
			(at 3.957828 0.479806 270)
			(unlocked yes)
			(layer "B.SilkS")
			(effects
				(font
					(size 0.7874 0.5842)
					(thickness 0.1524)
				)
				(justify left mirror)
			)
		)
		(property "Value" ""
			(at 0 0 90)
			(layer "B.Fab")
			(effects
				(font
					(size 1.27 1.27)
				)
				(justify mirror)
			)
		)
		(duplicate_pad_numbers_are_jumpers no)
		(fp_line
			(start 0.7874 -0.4064)
			(end -0.7874 -0.4064)
			(stroke
				(width 0.1524)
				(type default)
			)
			(layer "B.SilkS")
		)
		(fp_line
			(start -0.7874 -0.4064)
			(end -0.7874 0.4064)
			(stroke
				(width 0.1524)
				(type default)
			)
			(layer "B.SilkS")
		)
		(fp_line
			(start 0.7874 0.4064)
			(end 0.7874 -0.4064)
			(stroke
				(width 0.1524)
				(type default)
			)
			(layer "B.SilkS")
		)
		(fp_line
			(start -0.7874 0.4064)
			(end 0.7874 0.4064)
			(stroke
				(width 0.1524)
				(type default)
			)
			(layer "B.SilkS")
		)
		(fp_poly
			(pts
				(xy 0.508 0.2794) (xy 0.508 0.2286) (xy 0.635 0.2286) (xy 0.635 -0.254) (xy 0.5334 -0.254) (xy 0.5334 -0.2794)
				(xy -0.5334 -0.2794) (xy -0.5334 -0.254) (xy -0.635 -0.254) (xy -0.635 0.254) (xy -0.5334 0.254)
				(xy -0.5334 0.2794)
			)
			(stroke
				(width 0)
				(type default)
			)
			(fill no)
			(layer "B.CrtYd")
		)
		(pad "1" smd rect
			(at -0.40005 0 270)
			(size 0.4572 0.508)
			(layers "B.Cu" "B.Mask" "B.Paste")
			(net "UART_T7_NODE2_TXD")
		)
		(pad "2" smd rect
			(at 0.40005 0 270)
			(size 0.4572 0.508)
			(layers "B.Cu" "B.Mask" "B.Paste")
			(net "UART_T7_NODE2_TXD_R")
		)
	)
	(footprint ""
		(layer "B.Cu")
		(at 158.293308 -166.71798)
		(property "Reference" "U142"
			(at 0.123698 2.82702 0)
			(unlocked yes)
			(layer "B.SilkS")
			(effects
				(font
					(size 0.7874 0.5842)
					(thickness 0.1524)
				)
				(justify mirror)
			)
		)
		(property "Value" ""
			(at 0 0 0)
			(layer "B.Fab")
			(effects
				(font
					(size 1.27 1.27)
				)
				(justify mirror)
			)
		)
		(duplicate_pad_numbers_are_jumpers no)
		(fp_line
			(start -1.651 -1.905)
			(end -1.651 1.905)
			(stroke
				(width 0.1524)
				(type default)
			)
			(layer "B.SilkS")
		)
		(fp_line
			(start -1.651 1.905)
			(end 1.651 1.905)
			(stroke
				(width 0.1524)
				(type default)
			)
			(layer "B.SilkS")
		)
		(fp_line
			(start 1.651 -1.905)
			(end -1.651 -1.905)
			(stroke
				(width 0.1524)
				(type default)
			)
			(layer "B.SilkS")
		)
		(fp_line
			(start 1.651 1.905)
			(end 1.651 -1.905)
			(stroke
				(width 0.1524)
				(type default)
			)
			(layer "B.SilkS")
		)
		(fp_poly
			(pts
				(xy 1.524 0.7112) (xy 1.524 1.7526) (xy 0.508 1.7526) (xy 0.508 0.6985) (xy -0.508 0.6985) (xy -0.508 1.7526)
				(xy -1.524 1.7526) (xy -1.524 0.6985) (xy -1.524 -0.6985) (xy -0.508 -0.6985) (xy -0.508 -1.7526)
				(xy 0.508 -1.7526) (xy 0.508 -0.6985) (xy 1.524 -0.6985) (xy 1.524 0.6985)
			)
			(stroke
				(width 0)
				(type default)
			)
			(fill no)
			(layer "B.CrtYd")
		)
		(fp_text user "S"
			(at -2.135632 0.43942 90)
			(unlocked yes)
			(layer "B.SilkS")
			(effects
				(font
					(size 0.635 0.4064)
					(thickness 0.1524)
				)
				(justify mirror)
			)
		)
		(fp_text user "D"
			(at -0.96139 -2.471674 0)
			(unlocked yes)
			(layer "B.SilkS")
			(effects
				(font
					(size 0.635 0.4064)
					(thickness 0.1524)
				)
				(justify mirror)
			)
		)
		(fp_text user "G"
			(at 1.968246 1.998218 0)
			(unlocked yes)
			(layer "B.SilkS")
			(effects
				(font
					(size 0.635 0.4064)
					(thickness 0.1524)
				)
				(justify mirror)
			)
		)
		(pad "D" smd rect
			(at 0 -1.1176 180)
			(size 1.016 1.27)
			(layers "B.Cu" "B.Mask" "B.Paste")
			(net "CPLD_UART_RI_P4_N")
		)
		(pad "G" smd rect
			(at 1.016 1.1176 180)
			(size 1.016 1.27)
			(layers "B.Cu" "B.Mask" "B.Paste")
			(net "TACKOVER_EN")
		)
		(pad "S" smd rect
			(at -1.016 1.1176 180)
			(size 1.016 1.27)
			(layers "B.Cu" "B.Mask" "B.Paste")
			(net "CPLD_UART_RI_P4_LS_N")
		)
	)
)
